(kicad_pcb
	(version 20260206)
	(generator "pcbnew")
	(generator_version "10.0")
	(general
		(thickness 1.6)
		(legacy_teardrops no)
	)
	(paper "A4")
	(title_block
		(title "01162023_DA0F0TEBIF0_F0T_Expander_BD_F_brd_V02_OCP.brd")
		(comment 1 "Grand Teton / footprints 6788-6793 of 9728")
	)
	(layers
		(0 "F.Cu" signal "TOP")
		(4 "In1.Cu" signal "GND")
		(6 "In2.Cu" signal "VCC")
		(8 "In3.Cu" signal "VCC1")
		(10 "In4.Cu" signal "GND1")
		(12 "In5.Cu" signal "IN1")
		(14 "In6.Cu" signal "GND2")
		(16 "In7.Cu" signal "IN2")
		(18 "In8.Cu" signal "GND3")
		(20 "In9.Cu" signal "IN3")
		(22 "In10.Cu" signal "GND4")
		(24 "In11.Cu" signal "IN4")
		(26 "In12.Cu" signal "GND5")
		(28 "In13.Cu" signal "IN5")
		(30 "In14.Cu" signal "GND6")
		(32 "In15.Cu" signal "IN6")
		(34 "In16.Cu" signal "GND7")
		(2 "B.Cu" signal "BOTTOM")
		(9 "F.Adhes" user "F.Adhesive")
		(11 "B.Adhes" user "B.Adhesive")
		(13 "F.Paste" user "Package Geometry/Pastemask Top")
		(15 "B.Paste" user "Package Geometry/Pastemask Bottom")
		(5 "F.SilkS" user "Ref Des/Silkscreen Top")
		(7 "B.SilkS" user "Ref Des/Silkscreen Bottom")
		(1 "F.Mask" user "Board Geometry/Soldermask Top")
		(3 "B.Mask" user "Board Geometry/Soldermask Bottom")
		(17 "Dwgs.User" user "User.Drawings")
		(19 "Cmts.User" user "User.Comments")
		(21 "Eco1.User" user "User.Eco1")
		(23 "Eco2.User" user "User.Eco2")
		(25 "Edge.Cuts" user "Board Geometry/Outline")
		(27 "Margin" user)
		(31 "F.CrtYd" user "Package Geometry/Place Bound Top")
		(29 "B.CrtYd" user "Package Geometry/Place Bound Bottom")
		(35 "F.Fab" user "Ref Des/Assembly Top")
		(33 "B.Fab" user "Ref Des/Assembly Bottom")
	)
	(footprint ""
		(layer "F.Cu")
		(at 428.957486 -107.552998 -90)
		(property "Reference" "C951"
			(at 0 0 270)
			(layer "F.SilkS")
			(hide yes)
			(effects
				(font
					(size 1.27 1.27)
				)
			)
		)
		(property "Value" ""
			(at 0 0 270)
			(layer "F.Fab")
			(effects
				(font
					(size 1.27 1.27)
				)
			)
		)
		(duplicate_pad_numbers_are_jumpers no)
		(fp_line
			(start -1.524 0.762)
			(end -1.524 -0.762)
			(stroke
				(width 0.1524)
				(type default)
			)
			(layer "F.SilkS")
		)
		(fp_line
			(start 1.524 0.762)
			(end -1.524 0.762)
			(stroke
				(width 0.1524)
				(type default)
			)
			(layer "F.SilkS")
		)
		(fp_line
			(start -1.524 -0.762)
			(end 1.524 -0.762)
			(stroke
				(width 0.1524)
				(type default)
			)
			(layer "F.SilkS")
		)
		(fp_line
			(start 1.524 -0.762)
			(end 1.524 0.762)
			(stroke
				(width 0.1524)
				(type default)
			)
			(layer "F.SilkS")
		)
		(fp_line
			(start -1.1049 0.724916)
			(end 1.1049 0.724916)
			(stroke
				(width 0.1)
				(type default)
			)
			(layer "F.Fab")
		)
		(fp_line
			(start 1.1049 0.724916)
			(end 1.1049 -0.724916)
			(stroke
				(width 0.1)
				(type default)
			)
			(layer "F.Fab")
		)
		(fp_line
			(start -1.1049 -0.724916)
			(end -1.1049 0.724916)
			(stroke
				(width 0.1)
				(type default)
			)
			(layer "F.Fab")
		)
		(fp_line
			(start 1.1049 -0.724916)
			(end -1.1049 -0.724916)
			(stroke
				(width 0.1)
				(type default)
			)
			(layer "F.Fab")
		)
		(pad "1" smd rect
			(at -0.889 0 90)
			(size 1.016 1.27)
			(layers "F.Cu" "F.Mask" "F.Paste")
			(net "P12V_NIC7")
		)
		(pad "2" smd rect
			(at 0.889 0 90)
			(size 1.016 1.27)
			(layers "F.Cu" "F.Mask" "F.Paste")
			(net "GND")
		)
	)
	(footprint ""
		(layer "F.Cu")
		(at 79.332074 -32.848042 90)
		(property "Reference" "PC687"
			(at 0 0 90)
			(layer "F.SilkS")
			(hide yes)
			(effects
				(font
					(size 1.27 1.27)
				)
			)
		)
		(property "Value" ""
			(at 0 0 90)
			(layer "F.Fab")
			(effects
				(font
					(size 1.27 1.27)
				)
			)
		)
		(duplicate_pad_numbers_are_jumpers no)
		(fp_line
			(start 0.7874 -0.4064)
			(end 0.7874 0.4064)
			(stroke
				(width 0.1524)
				(type default)
			)
			(layer "F.SilkS")
		)
		(fp_line
			(start -0.7874 -0.4064)
			(end 0.7874 -0.4064)
			(stroke
				(width 0.1524)
				(type default)
			)
			(layer "F.SilkS")
		)
		(fp_line
			(start 0.7874 0.4064)
			(end -0.7874 0.4064)
			(stroke
				(width 0.1524)
				(type default)
			)
			(layer "F.SilkS")
		)
		(fp_line
			(start -0.7874 0.4064)
			(end -0.7874 -0.4064)
			(stroke
				(width 0.1524)
				(type default)
			)
			(layer "F.SilkS")
		)
		(fp_line
			(start -0.12065 -0.305054)
			(end -0.12065 -0.2794)
			(stroke
				(width 0.1)
				(type default)
			)
			(layer "F.Fab")
		)
		(fp_line
			(start -0.67945 -0.305054)
			(end -0.12065 -0.305054)
			(stroke
				(width 0.1)
				(type default)
			)
			(layer "F.Fab")
		)
		(fp_line
			(start 0.67945 -0.3048)
			(end 0.67945 0.3048)
			(stroke
				(width 0.1)
				(type default)
			)
			(layer "F.Fab")
		)
		(fp_line
			(start 0.12065 -0.3048)
			(end 0.67945 -0.3048)
			(stroke
				(width 0.1)
				(type default)
			)
			(layer "F.Fab")
		)
		(fp_line
			(start 0.12065 -0.2794)
			(end 0.12065 -0.3048)
			(stroke
				(width 0.1)
				(type default)
			)
			(layer "F.Fab")
		)
		(fp_line
			(start -0.12065 -0.2794)
			(end 0.12065 -0.2794)
			(stroke
				(width 0.1)
				(type default)
			)
			(layer "F.Fab")
		)
		(fp_line
			(start 0.120396 0.2794)
			(end -0.12065 0.2794)
			(stroke
				(width 0.1)
				(type default)
			)
			(layer "F.Fab")
		)
		(fp_line
			(start -0.12065 0.2794)
			(end -0.12065 0.3048)
			(stroke
				(width 0.1)
				(type default)
			)
			(layer "F.Fab")
		)
		(fp_line
			(start 0.67945 0.3048)
			(end 0.120396 0.3048)
			(stroke
				(width 0.1)
				(type default)
			)
			(layer "F.Fab")
		)
		(fp_line
			(start 0.120396 0.3048)
			(end 0.120396 0.2794)
			(stroke
				(width 0.1)
				(type default)
			)
			(layer "F.Fab")
		)
		(fp_line
			(start -0.12065 0.3048)
			(end -0.67945 0.3048)
			(stroke
				(width 0.1)
				(type default)
			)
			(layer "F.Fab")
		)
		(fp_line
			(start -0.67945 0.3048)
			(end -0.67945 -0.305054)
			(stroke
				(width 0.1)
				(type default)
			)
			(layer "F.Fab")
		)
		(pad "1" smd circle
			(at -0.40005 0 90)
			(size 0 0)
			(layers "F.Cu" "F.Mask" "F.Paste")
			(net "P3V3_SSD3_CO_DV_DT")
		)
		(pad "2" smd circle
			(at 0.40005 0 90)
			(size 0 0)
			(layers "F.Cu" "F.Mask" "F.Paste")
			(net "GND")
		)
	)
	(footprint ""
		(layer "F.Cu")
		(at 344.612976 -90.169746 180)
		(property "Reference" "R1183"
			(at 0 0 180)
			(layer "F.SilkS")
			(hide yes)
			(effects
				(font
					(size 1.27 1.27)
				)
			)
		)
		(property "Value" ""
			(at 0 0 180)
			(layer "F.Fab")
			(effects
				(font
					(size 1.27 1.27)
				)
			)
		)
		(duplicate_pad_numbers_are_jumpers no)
		(fp_line
			(start 0.7874 0.4064)
			(end -0.7874 0.4064)
			(stroke
				(width 0.1524)
				(type default)
			)
			(layer "F.SilkS")
		)
		(fp_line
			(start 0.67945 0.3048)
			(end 0.120396 0.3048)
			(stroke
				(width 0.1)
				(type default)
			)
			(layer "F.Fab")
		)
		(fp_line
			(start 0.67945 -0.3048)
			(end 0.67945 0.3048)
			(stroke
				(width 0.1)
				(type default)
			)
			(layer "F.Fab")
		)
		(fp_line
			(start 0.12065 -0.2794)
			(end 0.12065 -0.3048)
			(stroke
				(width 0.1)
				(type default)
			)
			(layer "F.Fab")
		)
		(fp_line
			(start 0.12065 -0.3048)
			(end 0.67945 -0.3048)
			(stroke
				(width 0.1)
				(type default)
			)
			(layer "F.Fab")
		)
		(fp_line
			(start 0.120396 0.3048)
			(end 0.120396 0.2794)
			(stroke
				(width 0.1)
				(type default)
			)
			(layer "F.Fab")
		)
		(fp_line
			(start 0.120396 0.2794)
			(end -0.12065 0.2794)
			(stroke
				(width 0.1)
				(type default)
			)
			(layer "F.Fab")
		)
		(fp_line
			(start -0.12065 0.3048)
			(end -0.67945 0.3048)
			(stroke
				(width 0.1)
				(type default)
			)
			(layer "F.Fab")
		)
		(fp_line
			(start -0.12065 0.2794)
			(end -0.12065 0.3048)
			(stroke
				(width 0.1)
				(type default)
			)
			(layer "F.Fab")
		)
		(fp_line
			(start -0.12065 -0.2794)
			(end 0.12065 -0.2794)
			(stroke
				(width 0.1)
				(type default)
			)
			(layer "F.Fab")
		)
		(fp_line
			(start -0.12065 -0.305054)
			(end -0.12065 -0.2794)
			(stroke
				(width 0.1)
				(type default)
			)
			(layer "F.Fab")
		)
		(fp_line
			(start -0.67945 0.3048)
			(end -0.67945 -0.305054)
			(stroke
				(width 0.1)
				(type default)
			)
			(layer "F.Fab")
		)
		(fp_line
			(start -0.67945 -0.305054)
			(end -0.12065 -0.305054)
			(stroke
				(width 0.1)
				(type default)
			)
			(layer "F.Fab")
		)
		(pad "1" smd circle
			(at -0.40005 0 180)
			(size 0 0)
			(layers "F.Cu" "F.Mask" "F.Paste")
			(net "CLK_100M_DB800ZL_SSD14_R_DN")
		)
		(pad "2" smd circle
			(at 0.40005 0 180)
			(size 0 0)
			(layers "F.Cu" "F.Mask" "F.Paste")
			(net "CLK_100M_DB800ZL_SSD14_DN")
		)
	)
	(footprint ""
		(layer "F.Cu")
		(at 48.647096 -54.3941)
		(property "Reference" "PU32"
			(at -1.707642 3.085592 0)
			(unlocked yes)
			(layer "F.SilkS")
			(effects
				(font
					(size 0.7874 0.5842)
					(thickness 0.1524)
				)
				(justify left)
			)
		)
		(property "Value" ""
			(at 0 0 0)
			(layer "F.Fab")
			(effects
				(font
					(size 1.27 1.27)
				)
			)
		)
		(duplicate_pad_numbers_are_jumpers no)
		(fp_line
			(start -1.943608 -1.549908)
			(end 1.943608 -1.549908)
			(stroke
				(width 0.1524)
				(type default)
			)
			(layer "F.SilkS")
		)
		(fp_line
			(start -1.943608 1.549908)
			(end -1.943608 -1.549908)
			(stroke
				(width 0.1524)
				(type default)
			)
			(layer "F.SilkS")
		)
		(fp_line
			(start 1.943608 -1.549908)
			(end 1.943608 1.549908)
			(stroke
				(width 0.1524)
				(type default)
			)
			(layer "F.SilkS")
		)
		(fp_line
			(start 1.943608 1.549908)
			(end -1.943608 1.549908)
			(stroke
				(width 0.1524)
				(type default)
			)
			(layer "F.SilkS")
		)
		(fp_poly
			(pts
				(xy -2.019808 -1.549908) (xy -1.257808 -1.549908) (xy -1.257808 -1.880108) (xy -2.019808 -1.880108)
			)
			(stroke
				(width 0)
				(type default)
			)
			(fill yes)
			(layer "F.SilkS")
		)
		(fp_line
			(start -1.549908 -1.549908)
			(end 1.549908 -1.549908)
			(stroke
				(width 0.1)
				(type default)
			)
			(layer "F.Fab")
		)
		(fp_line
			(start -1.549908 1.549908)
			(end -1.549908 -1.549908)
			(stroke
				(width 0.1)
				(type default)
			)
			(layer "F.Fab")
		)
		(fp_line
			(start 1.549908 -1.549908)
			(end 1.549908 1.549908)
			(stroke
				(width 0.1)
				(type default)
			)
			(layer "F.Fab")
		)
		(fp_line
			(start 1.549908 1.549908)
			(end -1.549908 1.549908)
			(stroke
				(width 0.1)
				(type default)
			)
			(layer "F.Fab")
		)
		(fp_poly
			(pts
				(xy -2.019808 -1.549908) (xy -1.257808 -1.549908) (xy -1.257808 -1.880108) (xy -2.019808 -1.880108)
			)
			(stroke
				(width 0)
				(type default)
			)
			(fill yes)
			(layer "F.Fab")
		)
		(pad "1" smd rect
			(at -1.500124 -1.249934 270)
			(size 0.2794 0.6096)
			(layers "F.Cu" "F.Mask" "F.Paste")
			(net "P12V_SSD1_R")
		)
		(pad "2" smd rect
			(at -1.500124 -0.750062 270)
			(size 0.2794 0.6096)
			(layers "F.Cu" "F.Mask" "F.Paste")
			(net "P12V_SSD1_R")
		)
		(pad "3" smd rect
			(at -1.500124 -0.249936 270)
			(size 0.2794 0.6096)
			(layers "F.Cu" "F.Mask" "F.Paste")
			(net "P12V_SSD1_R")
		)
		(pad "4" smd rect
			(at -1.500124 0.249936 270)
			(size 0.2794 0.6096)
			(layers "F.Cu" "F.Mask" "F.Paste")
			(net "P12V_SSD1_R")
		)
		(pad "5" smd rect
			(at -1.500124 0.750062 270)
			(size 0.2794 0.6096)
			(layers "F.Cu" "F.Mask" "F.Paste")
			(net "P12V_SSD1_R")
		)
		(pad "6" smd rect
			(at -1.500124 1.249934 270)
			(size 0.2794 0.6096)
			(layers "F.Cu" "F.Mask" "F.Paste")
			(net "GND")
		)
		(pad "7" smd rect
			(at 1.500124 1.249934 270)
			(size 0.2794 0.6096)
			(layers "F.Cu" "F.Mask" "F.Paste")
			(net "P12V_SSD1_SS")
		)
		(pad "8" smd rect
			(at 1.500124 0.750062 270)
			(size 0.2794 0.6096)
			(layers "F.Cu" "F.Mask" "F.Paste")
			(net "PWRGD_P12V_SSD1")
		)
		(pad "9" smd rect
			(at 1.500124 0.249936 270)
			(size 0.2794 0.6096)
			(layers "F.Cu" "F.Mask" "F.Paste")
			(net "P12V_SSD1_OCP")
		)
		(pad "10" smd rect
			(at 1.500124 -0.249936 270)
			(size 0.2794 0.6096)
			(layers "F.Cu" "F.Mask" "F.Paste")
			(net "P5V_AUX")
		)
		(pad "11" smd rect
			(at 1.500124 -0.750062 270)
			(size 0.2794 0.6096)
			(layers "F.Cu" "F.Mask" "F.Paste")
			(net "SSD1_PWR_EN_R")
		)
		(pad "12" smd rect
			(at 1.500124 -1.249934 270)
			(size 0.2794 0.6096)
			(layers "F.Cu" "F.Mask" "F.Paste")
			(net "P12V_AUX")
		)
		(pad "13" smd rect
			(at 0 0)
			(size 1.9812 2.7178)
			(layers "F.Cu" "F.Mask" "F.Paste")
			(net "P12V_AUX")
		)
		(zone
			(layer "F.Cu")
			(hatch none 0.5)
			(connect_pads
				(clearance 0)
			)
			(min_thickness 0.25)
			(keepout
				(tracks not_allowed)
				(vias allowed)
				(pads allowed)
				(copperpour not_allowed)
				(footprints allowed)
			)
			(placement
				(enabled no)
				(sheetname "")
			)
			(fill
				(thermal_gap 0.5)
				(thermal_bridge_width 0.5)
				(island_removal_mode 0)
			)
			(polygon
				(pts
					(xy 49.790096 -55.9435) (xy 49.790096 -55.8165) (xy 49.790096 -52.8447) (xy 49.790096 -52.844192)
					(xy 47.504096 -52.844192) (xy 47.504096 -52.8447) (xy 47.504096 -52.9717) (xy 47.504096 -54.3941)
					(xy 47.605696 -54.3941) (xy 47.605696 -52.9717) (xy 49.688496 -52.9717) (xy 49.688496 -55.8165)
					(xy 47.605696 -55.8165) (xy 47.605696 -54.4195) (xy 47.504096 -54.4195) (xy 47.504096 -55.8165)
					(xy 47.504096 -55.9435) (xy 47.504096 -55.944008) (xy 49.790096 -55.944008)
				)
			)
		)
	)
	(footprint ""
		(layer "F.Cu")
		(at 282.315412 -42.853102 180)
		(property "Reference" "R5899"
			(at 0 0 180)
			(layer "F.SilkS")
			(hide yes)
			(effects
				(font
					(size 1.27 1.27)
				)
			)
		)
		(property "Value" ""
			(at 0 0 180)
			(layer "F.Fab")
			(effects
				(font
					(size 1.27 1.27)
				)
			)
		)
		(duplicate_pad_numbers_are_jumpers no)
		(fp_line
			(start 0.7874 0.4064)
			(end -0.7874 0.4064)
			(stroke
				(width 0.1524)
				(type default)
			)
			(layer "F.SilkS")
		)
		(fp_line
			(start 0.7874 -0.4064)
			(end 0.7874 0.4064)
			(stroke
				(width 0.1524)
				(type default)
			)
			(layer "F.SilkS")
		)
		(fp_line
			(start -0.7874 0.4064)
			(end -0.7874 -0.4064)
			(stroke
				(width 0.1524)
				(type default)
			)
			(layer "F.SilkS")
		)
		(fp_line
			(start -0.7874 -0.4064)
			(end 0.7874 -0.4064)
			(stroke
				(width 0.1524)
				(type default)
			)
			(layer "F.SilkS")
		)
		(fp_line
			(start 0.67945 0.3048)
			(end 0.120396 0.3048)
			(stroke
				(width 0.1)
				(type default)
			)
			(layer "F.Fab")
		)
		(fp_line
			(start 0.67945 -0.3048)
			(end 0.67945 0.3048)
			(stroke
				(width 0.1)
				(type default)
			)
			(layer "F.Fab")
		)
		(fp_line
			(start 0.12065 -0.2794)
			(end 0.12065 -0.3048)
			(stroke
				(width 0.1)
				(type default)
			)
			(layer "F.Fab")
		)
		(fp_line
			(start 0.12065 -0.3048)
			(end 0.67945 -0.3048)
			(stroke
				(width 0.1)
				(type default)
			)
			(layer "F.Fab")
		)
		(fp_line
			(start 0.120396 0.3048)
			(end 0.120396 0.2794)
			(stroke
				(width 0.1)
				(type default)
			)
			(layer "F.Fab")
		)
		(fp_line
			(start 0.120396 0.2794)
			(end -0.12065 0.2794)
			(stroke
				(width 0.1)
				(type default)
			)
			(layer "F.Fab")
		)
		(fp_line
			(start -0.12065 0.3048)
			(end -0.67945 0.3048)
			(stroke
				(width 0.1)
				(type default)
			)
			(layer "F.Fab")
		)
		(fp_line
			(start -0.12065 0.2794)
			(end -0.12065 0.3048)
			(stroke
				(width 0.1)
				(type default)
			)
			(layer "F.Fab")
		)
		(fp_line
			(start -0.12065 -0.2794)
			(end 0.12065 -0.2794)
			(stroke
				(width 0.1)
				(type default)
			)
			(layer "F.Fab")
		)
		(fp_line
			(start -0.12065 -0.305054)
			(end -0.12065 -0.2794)
			(stroke
				(width 0.1)
				(type default)
			)
			(layer "F.Fab")
		)
		(fp_line
			(start -0.67945 0.3048)
			(end -0.67945 -0.305054)
			(stroke
				(width 0.1)
				(type default)
			)
			(layer "F.Fab")
		)
		(fp_line
			(start -0.67945 -0.305054)
			(end -0.12065 -0.305054)
			(stroke
				(width 0.1)
				(type default)
			)
			(layer "F.Fab")
		)
		(pad "1" smd circle
			(at -0.40005 0 180)
			(size 0 0)
			(layers "F.Cu" "F.Mask" "F.Paste")
			(net "SSD9_ADC_A1")
		)
		(pad "2" smd circle
			(at 0.40005 0 180)
			(size 0 0)
			(layers "F.Cu" "F.Mask" "F.Paste")
			(net "SMB_SSD9_ADC_SDA")
		)
	)
	(footprint ""
		(layer "F.Cu")
		(at 2.71526 -380.182628 180)
		(property "Reference" "C4460"
			(at 0 0 180)
			(layer "F.SilkS")
			(hide yes)
			(effects
				(font
					(size 1.27 1.27)
				)
			)
		)
		(property "Value" ""
			(at 0 0 180)
			(layer "F.Fab")
			(effects
				(font
					(size 1.27 1.27)
				)
			)
		)
		(duplicate_pad_numbers_are_jumpers no)
		(fp_line
			(start 0.7874 0.4064)
			(end -0.7874 0.4064)
			(stroke
				(width 0.1524)
				(type default)
			)
			(layer "F.SilkS")
		)
		(fp_line
			(start 0.7874 -0.4064)
			(end 0.7874 0.4064)
			(stroke
				(width 0.1524)
				(type default)
			)
			(layer "F.SilkS")
		)
		(fp_line
			(start -0.7874 0.4064)
			(end -0.7874 -0.4064)
			(stroke
				(width 0.1524)
				(type default)
			)
			(layer "F.SilkS")
		)
		(fp_line
			(start -0.7874 -0.4064)
			(end 0.7874 -0.4064)
			(stroke
				(width 0.1524)
				(type default)
			)
			(layer "F.SilkS")
		)
		(fp_line
			(start 0.67945 0.3048)
			(end 0.120396 0.3048)
			(stroke
				(width 0.1)
				(type default)
			)
			(layer "F.Fab")
		)
		(fp_line
			(start 0.67945 -0.3048)
			(end 0.67945 0.3048)
			(stroke
				(width 0.1)
				(type default)
			)
			(layer "F.Fab")
		)
		(fp_line
			(start 0.12065 -0.2794)
			(end 0.12065 -0.3048)
			(stroke
				(width 0.1)
				(type default)
			)
			(layer "F.Fab")
		)
		(fp_line
			(start 0.12065 -0.3048)
			(end 0.67945 -0.3048)
			(stroke
				(width 0.1)
				(type default)
			)
			(layer "F.Fab")
		)
		(fp_line
			(start 0.120396 0.3048)
			(end 0.120396 0.2794)
			(stroke
				(width 0.1)
				(type default)
			)
			(layer "F.Fab")
		)
		(fp_line
			(start 0.120396 0.2794)
			(end -0.12065 0.2794)
			(stroke
				(width 0.1)
				(type default)
			)
			(layer "F.Fab")
		)
		(fp_line
			(start -0.12065 0.3048)
			(end -0.67945 0.3048)
			(stroke
				(width 0.1)
				(type default)
			)
			(layer "F.Fab")
		)
		(fp_line
			(start -0.12065 0.2794)
			(end -0.12065 0.3048)
			(stroke
				(width 0.1)
				(type default)
			)
			(layer "F.Fab")
		)
		(fp_line
			(start -0.12065 -0.2794)
			(end 0.12065 -0.2794)
			(stroke
				(width 0.1)
				(type default)
			)
			(layer "F.Fab")
		)
		(fp_line
			(start -0.12065 -0.305054)
			(end -0.12065 -0.2794)
			(stroke
				(width 0.1)
				(type default)
			)
			(layer "F.Fab")
		)
		(fp_line
			(start -0.67945 0.3048)
			(end -0.67945 -0.305054)
			(stroke
				(width 0.1)
				(type default)
			)
			(layer "F.Fab")
		)
		(fp_line
			(start -0.67945 -0.305054)
			(end -0.12065 -0.305054)
			(stroke
				(width 0.1)
				(type default)
			)
			(layer "F.Fab")
		)
		(pad "1" smd circle
			(at -0.40005 0 180)
			(size 0 0)
			(layers "F.Cu" "F.Mask" "F.Paste")
			(net "BIC_USB_8042_HUB_XOUT")
		)
		(pad "2" smd circle
			(at 0.40005 0 180)
			(size 0 0)
			(layers "F.Cu" "F.Mask" "F.Paste")
			(net "GND")
		)
	)
)
